# BASEBOARD_FAB2 (Tioga Pass) — schematic netlist excerpt (pin names and nets, part order shuffled) for the footprints in the layout excerpt that follows; sources: Cadence DE-HDL packaged netlist, KiCad conversion of Wiwynn_Tioga_Pass_MB.brd

R2U47  RES  0.0 5% CHIP  pkg 0402  page 152 : A = H_CPU0_MEMABC_MEMHOT_LVT3_N ; B = H_CPU0_MEMABC_MEMHOT_LVT3_BMC_N
R3P6  RES  1.00K 1% EMPTY  pkg 0402  page 133 : A = P1V05_PCH_STBY ; B = FM_PRSNT_2_3_N
R8W15  RES  4.75K 1% CHIP  pkg 0402  page 245 : A = P3V3_STBY ; B = JTAG_RISER_N

(kicad_pcb
	(version 20260206)
	(generator "pcbnew")
	(generator_version "10.0")
	(general
		(thickness 1.6)
		(legacy_teardrops no)
	)
	(paper "A4")
	(title_block
		(title "Wiwynn_Tioga_Pass_MB.brd")
		(comment 1 "Tioga Pass / footprints 4751-4753 of 4770")
	)
	(layers
		(0 "F.Cu" signal "TOP")
		(4 "In1.Cu" signal "L2GND")
		(6 "In2.Cu" signal "L3")
		(8 "In3.Cu" signal "L4GND")
		(10 "In4.Cu" signal "L5")
		(12 "In5.Cu" signal "L6GND")
		(14 "In6.Cu" signal "L7VCC")
		(16 "In7.Cu" signal "L8VCC")
		(18 "In8.Cu" signal "L9GND")
		(20 "In9.Cu" signal "L10")
		(22 "In10.Cu" signal "L11GND")
		(24 "In11.Cu" signal "L12")
		(26 "In12.Cu" signal "L13GND")
		(2 "B.Cu" signal "BOTTOM")
		(9 "F.Adhes" user "F.Adhesive")
		(11 "B.Adhes" user "B.Adhesive")
		(13 "F.Paste" user "Package Geometry/Pastemask Top")
		(15 "B.Paste" user "Package Geometry/Pastemask Bottom")
		(5 "F.SilkS" user "Ref Des/Silkscreen Top")
		(7 "B.SilkS" user "Ref Des/Silkscreen Bottom")
		(1 "F.Mask" user "Board Geometry/Soldermask Top")
		(3 "B.Mask" user "Board Geometry/Soldermask Bottom")
		(17 "Dwgs.User" user "User.Drawings")
		(19 "Cmts.User" user "User.Comments")
		(21 "Eco1.User" user "User.Eco1")
		(23 "Eco2.User" user "User.Eco2")
		(25 "Edge.Cuts" user "Board Geometry/Outline")
		(27 "Margin" user)
		(31 "F.CrtYd" user "Package Geometry/Place Bound Top")
		(29 "B.CrtYd" user "Package Geometry/Place Bound Bottom")
		(35 "F.Fab" user "Ref Des/Assembly Top")
		(33 "B.Fab" user "Ref Des/Assembly Bottom")
	)
	(footprint ""
		(layer "B.Cu")
		(at 381.4826 -3.185414 90)
		(property "Reference" "R8W15"
			(at 0.8382 -0.67818 90)
			(unlocked yes)
			(layer "B.SilkS")
			(effects
				(font
					(size 0.4064 0.254)
					(thickness 0.1524)
				)
				(justify left mirror)
			)
		)
		(property "Value" ""
			(at 0 0 90)
			(layer "B.Fab")
			(effects
				(font
					(size 1.27 1.27)
				)
				(justify mirror)
			)
		)
		(duplicate_pad_numbers_are_jumpers no)
		(fp_poly
			(pts
				(xy 0.2794 -0.1016) (xy -0.2794 -0.1016) (xy -0.2794 0.9906) (xy 0.2794 0.9906)
			)
			(stroke
				(width 0)
				(type default)
			)
			(fill no)
			(layer "B.CrtYd")
		)
		(fp_line
			(start 0.2794 -0.1016)
			(end 0.2794 0.9906)
			(stroke
				(width 0.1)
				(type default)
			)
			(layer "B.Fab")
		)
		(fp_line
			(start -0.2794 -0.1016)
			(end 0.2794 -0.1016)
			(stroke
				(width 0.1)
				(type default)
			)
			(layer "B.Fab")
		)
		(fp_line
			(start 0.2794 0.9906)
			(end -0.2794 0.9906)
			(stroke
				(width 0.1)
				(type default)
			)
			(layer "B.Fab")
		)
		(fp_line
			(start -0.2794 0.9906)
			(end -0.2794 -0.1016)
			(stroke
				(width 0.1)
				(type default)
			)
			(layer "B.Fab")
		)
		(pad "1" smd rect
			(at 0 0 270)
			(size 0.508 0.508)
			(layers "B.Cu" "B.Mask" "B.Paste")
			(net "P3V3_STBY")
		)
		(pad "2" smd rect
			(at 0 0.889 270)
			(size 0.508 0.508)
			(layers "B.Cu" "B.Mask" "B.Paste")
			(net "JTAG_RISER_N")
		)
		(zone
			(layer "B.Cu")
			(hatch none 0.5)
			(connect_pads
				(clearance 0)
			)
			(min_thickness 0.25)
			(keepout
				(tracks allowed)
				(vias not_allowed)
				(pads allowed)
				(copperpour not_allowed)
				(footprints allowed)
			)
			(placement
				(enabled no)
				(sheetname "")
			)
			(fill
				(thermal_gap 0.5)
				(thermal_bridge_width 0.5)
				(island_removal_mode 0)
			)
			(polygon
				(pts
					(xy 381.7366 -3.439414) (xy 381.7366 -2.931414) (xy 382.1176 -2.931414) (xy 382.1176 -3.439414)
				)
			)
		)
		(zone
			(layer "B.Cu")
			(hatch none 0.5)
			(connect_pads
				(clearance 0)
			)
			(min_thickness 0.25)
			(keepout
				(tracks not_allowed)
				(vias allowed)
				(pads allowed)
				(copperpour not_allowed)
				(footprints allowed)
			)
			(placement
				(enabled no)
				(sheetname "")
			)
			(fill
				(thermal_gap 0.5)
				(thermal_bridge_width 0.5)
				(island_removal_mode 0)
			)
			(polygon
				(pts
					(xy 382.1176 -3.439414) (xy 382.1176 -2.931414) (xy 381.7366 -2.931414) (xy 381.7366 -3.439414)
				)
			)
		)
	)
	(footprint ""
		(layer "B.Cu")
		(at 386.575808 -84.729828 180)
		(property "Reference" "R3P6"
			(at 0.8382 -0.67818 180)
			(unlocked yes)
			(layer "B.SilkS")
			(effects
				(font
					(size 0.4064 0.254)
					(thickness 0.1524)
				)
				(justify left mirror)
			)
		)
		(property "Value" ""
			(at 0 0 0)
			(layer "B.Fab")
			(effects
				(font
					(size 1.27 1.27)
				)
				(justify mirror)
			)
		)
		(duplicate_pad_numbers_are_jumpers no)
		(fp_poly
			(pts
				(xy 0.2794 -0.1016) (xy -0.2794 -0.1016) (xy -0.2794 0.9906) (xy 0.2794 0.9906)
			)
			(stroke
				(width 0)
				(type default)
			)
			(fill no)
			(layer "B.CrtYd")
		)
		(fp_line
			(start 0.2794 0.9906)
			(end -0.2794 0.9906)
			(stroke
				(width 0.1)
				(type default)
			)
			(layer "B.Fab")
		)
		(fp_line
			(start 0.2794 -0.1016)
			(end 0.2794 0.9906)
			(stroke
				(width 0.1)
				(type default)
			)
			(layer "B.Fab")
		)
		(fp_line
			(start -0.2794 0.9906)
			(end -0.2794 -0.1016)
			(stroke
				(width 0.1)
				(type default)
			)
			(layer "B.Fab")
		)
		(fp_line
			(start -0.2794 -0.1016)
			(end 0.2794 -0.1016)
			(stroke
				(width 0.1)
				(type default)
			)
			(layer "B.Fab")
		)
		(pad "1" smd rect
			(at 0 0)
			(size 0.508 0.508)
			(layers "B.Cu" "B.Mask" "B.Paste")
			(net "P1V05_PCH_STBY")
		)
		(pad "2" smd rect
			(at 0 0.889)
			(size 0.508 0.508)
			(layers "B.Cu" "B.Mask" "B.Paste")
			(net "FM_PRSNT_2_3_N")
		)
		(zone
			(layer "B.Cu")
			(hatch none 0.5)
			(connect_pads
				(clearance 0)
			)
			(min_thickness 0.25)
			(keepout
				(tracks not_allowed)
				(vias allowed)
				(pads allowed)
				(copperpour not_allowed)
				(footprints allowed)
			)
			(placement
				(enabled no)
				(sheetname "")
			)
			(fill
				(thermal_gap 0.5)
				(thermal_bridge_width 0.5)
				(island_removal_mode 0)
			)
			(polygon
				(pts
					(xy 386.321808 -85.364828) (xy 386.829808 -85.364828) (xy 386.829808 -84.983828) (xy 386.321808 -84.983828)
				)
			)
		)
		(zone
			(layer "B.Cu")
			(hatch none 0.5)
			(connect_pads
				(clearance 0)
			)
			(min_thickness 0.25)
			(keepout
				(tracks allowed)
				(vias not_allowed)
				(pads allowed)
				(copperpour not_allowed)
				(footprints allowed)
			)
			(placement
				(enabled no)
				(sheetname "")
			)
			(fill
				(thermal_gap 0.5)
				(thermal_bridge_width 0.5)
				(island_removal_mode 0)
			)
			(polygon
				(pts
					(xy 386.321808 -84.983828) (xy 386.829808 -84.983828) (xy 386.829808 -85.364828) (xy 386.321808 -85.364828)
				)
			)
		)
	)
	(footprint ""
		(layer "B.Cu")
		(at 426.0215 -11.684 -90)
		(property "Reference" "R2U47"
			(at 0 0 90)
			(layer "B.SilkS")
			(hide yes)
			(effects
				(font
					(size 1.27 1.27)
				)
				(justify mirror)
			)
		)
		(property "Value" ""
			(at 0 0 90)
			(layer "B.Fab")
			(effects
				(font
					(size 1.27 1.27)
				)
				(justify mirror)
			)
		)
		(duplicate_pad_numbers_are_jumpers no)
		(fp_poly
			(pts
				(xy 0.2794 -0.1016) (xy -0.2794 -0.1016) (xy -0.2794 0.9906) (xy 0.2794 0.9906)
			)
			(stroke
				(width 0)
				(type default)
			)
			(fill no)
			(layer "B.CrtYd")
		)
		(fp_line
			(start -0.2794 0.9906)
			(end -0.2794 -0.1016)
			(stroke
				(width 0.1)
				(type default)
			)
			(layer "B.Fab")
		)
		(fp_line
			(start 0.2794 0.9906)
			(end -0.2794 0.9906)
			(stroke
				(width 0.1)
				(type default)
			)
			(layer "B.Fab")
		)
		(fp_line
			(start -0.2794 -0.1016)
			(end 0.2794 -0.1016)
			(stroke
				(width 0.1)
				(type default)
			)
			(layer "B.Fab")
		)
		(fp_line
			(start 0.2794 -0.1016)
			(end 0.2794 0.9906)
			(stroke
				(width 0.1)
				(type default)
			)
			(layer "B.Fab")
		)
		(pad "1" smd rect
			(at 0 0 90)
			(size 0.508 0.508)
			(layers "B.Cu" "B.Mask" "B.Paste")
			(net "H_CPU0_MEMABC_MEMHOT_LVT3_N")
		)
		(pad "2" smd rect
			(at 0 0.889 90)
			(size 0.508 0.508)
			(layers "B.Cu" "B.Mask" "B.Paste")
			(net "H_CPU0_MEMABC_MEMHOT_LVT3_BMC_N")
		)
		(zone
			(layer "B.Cu")
			(hatch none 0.5)
			(connect_pads
				(clearance 0)
			)
			(min_thickness 0.25)
			(keepout
				(tracks not_allowed)
				(vias allowed)
				(pads allowed)
				(copperpour not_allowed)
				(footprints allowed)
			)
			(placement
				(enabled no)
				(sheetname "")
			)
			(fill
				(thermal_gap 0.5)
				(thermal_bridge_width 0.5)
				(island_removal_mode 0)
			)
			(polygon
				(pts
					(xy 425.3865 -11.43) (xy 425.3865 -11.938) (xy 425.7675 -11.938) (xy 425.7675 -11.43)
				)
			)
		)
		(zone
			(layer "B.Cu")
			(hatch none 0.5)
			(connect_pads
				(clearance 0)
			)
			(min_thickness 0.25)
			(keepout
				(tracks allowed)
				(vias not_allowed)
				(pads allowed)
				(copperpour not_allowed)
				(footprints allowed)
			)
			(placement
				(enabled no)
				(sheetname "")
			)
			(fill
				(thermal_gap 0.5)
				(thermal_bridge_width 0.5)
				(island_removal_mode 0)
			)
			(polygon
				(pts
					(xy 425.7675 -11.43) (xy 425.7675 -11.938) (xy 425.3865 -11.938) (xy 425.3865 -11.43)
				)
			)
		)
	)
)
